# S9S_MB_2U (Grand Teton) — schematic netlist excerpt (pin names and nets, part order shuffled) for the footprints in the layout excerpt that follows; sources: Cadence DE-HDL packaged netlist, KiCad conversion of 03242023_DA0F0TMBIJ0_F0T_Motherboard_J_brd_V01_OCP.brd

J41  SCONN168_ME1016810202011  IO  pkg CON_F168S2H7D_P0-6W2-95_LUH  page 240
  GND_A1  = SMB_OCP_SFF_3V3AUX_SCL_R0
  GND_A2  = SMB_OCP_SFF_3V3AUX_SDA_R0
  GND_A3  = SMB_HOST_3V3AUX_SCL_R0
  GND_A4  = SMB_HOST_3V3AUX_SDA_R0
  GND_A5  = SMB_VR_3V3AUX_SCL_R0
  GND_A6  = SMB_VR_3V3AUX_SDA_R0
  SMCLK  = SMB_SML1_PMBUS_3V3AUX_PCH_SCL_R
  SMDAT  = SMB_SML1_PMBUS_3V3AUX_PCH_SDA_R
  \smrst#\  = I3C_BMC_SWB_SCL
  \prsnta#\  = I3C_BMC_SWB_SDA
  \perst1#\  = SMB_OCP_V3_2_3V3AUX_SCL_R0
  \prsntb2#\  = SMB_OCP_V3_2_3V3AUX_SDA_R0
  GND_A13  = GND
  REFCLKN1  = CLK_100M_BMC_P3E_DP_R
  REFCLKP1  = CLK_100M_BMC_P3E_DN_R
  GND_A16  = GND
  PERN0  = P3E_PCH_BMC_TX_C_DP
  PERP0  = P3E_PCH_BMC_TX_C_DN
  GND_A19  = GND
  PERN1  = P3E_PCH_BMC_RX_DP
  PERP1  = P3E_PCH_BMC_RX_DN
  GND_A22  = GND
  PERN2  = SMB_PCIE0_3V3AUX_SCL
  PERP2  = SMB_PCIE0_3V3AUX_SDA
  GND_A25  = SMB_SML0_3V3AUX_SCL_R1
  PERN3  = SMB_SML0_3V3AUX_SDA_R1
  PERP3  = SMB_1_PLD_3V3AUX_SCL_R3
  GND_A28  = SMB_1_PLD_3V3AUX_SDA_R3
  GND_A29  = SMB_FAN_3V3AUX_SCL
  PERN4  = SMB_FAN_3V3AUX_SDA
  PERP4  = SMB_PCIE2_3V3AUX_SCL_R0
  GND_A32  = SMB_PCIE2_3V3AUX_SDA_R0
  PERN5  = GND
  PERP5  = JTAG_BMC_TCK
  GND_A35  = JTAG_BMC_TMS
  PERN6  = JTAG_BMC_TDI
  PERP6  = JTAG_BMC_TDO
  GND_A38  = SMB_PCIE3_3V3AUX_SCL_R
  PERN7  = SMB_PCIE3_3V3AUX_SDA_R
  PERP7  = SMB_S3M_CPU_3V3AUX_SCL_R0
  GND_A41  = SMB_S3M_CPU_3V3AUX_SDA_R0
  \prsntb1#\  = GND
  GND_A43  = FM_JTAG_BMC_MUX_SEL_FROM_BMC_R2
  PERN8  = PWRGD_PS_PWROK_R
  PERP8  = TP_HPM_STBY_EN
  GND_A46  = RST_MB_STBY_N
  PERN9  = FM_BMC_PWRBTN_OUT_R_N
  PERP9  = PWRGD_SYS_PWROK
  GND_A49  = JTAG_BMC_DBP_PREQ_N
  PERN10  = JTAG_DBP_BMC_PRDY_N
  PERP10  = RST_PLTRST_B_N
  GND_A52  = FM_UARTSW_MSB_R
  PERN11  = ROT_P1_RST_IND_N
  PERP11  = FM_BMC_INTRUDER_N
  GND_A55  = FM_UARTSW_LSB_R
  PERN12  = IRQ0_A57
  PERP12  = FM_SCM_PRSNT1_N
  GND_A58  = GND
  PERN13  = USB3_PCH_RX_DP<4>
  PERP13  = USB3_PCH_RX_DN<4>
  GND_A61  = GND
  PERN14  = TP_PCIE_HPM_RXP<1>
  PERP14  = TP_PCIE_HPM_RXN<1>
  GND_A64  = GND
  PERN15  = P2E_MB_BMC_RX_BUF_DP<0>
  PERP15  = P2E_MB_BMC_RX_BUF_DN<0>
  GND_A67  = GND
  USB_DATN  = CLK_100M_BMC_RC_DP
  USB_DATP  = CLK_100M_BMC_RC_DN
  \pwrbrk0#\  = GND
  \+12v_edge_b1\  = ESPI_HOST_LPC_BMC_CLK
  \+12v_edge_b2\  = ESPI_HOST_LPC_BMC_LFRAME_N
  \+12v_edge_b3\  = IRQ_ESPI_LPC_SERIRQ_ALERT_R_N
  \+12v_edge_b4\  = ESPI_BMC_LPC_RST_N
  \+12v_edge_b5\  = ESPI_LPC_LAD0_IO0
  \+12v_edge_b6\  = ESPI_LPC_LAD0_IO1
  \bif0#\  = ESPI_LPC_LAD0_IO2
  \bif1#\  = ESPI_LPC_LAD0_IO3
  \bif2#\  = FM_LPC_ESPI_SEL
  \perst0#\  = GND
  \+3.3v_edge\  = SPI_SYS_CLK
  AUX_PWR_EN  = SPI_SYS_CS0_N
  GND_B13  = SPI_SYS_MOSI
  REFCLKN0  = SPI_SYS_MISO
  REFCLKP0  = SPI_SYS_WP_IO2
  GND_B16  = SPI_SYS_HOLD_IO3
  PETN0  = GND
  PETP0  = CLK_50M_RMII_BMC_OCP
  GND_B19  = RMII_OCP_BMC_CRSDV
  PETN1  = RMII_BMC_OCP_TX_EN
  PETP1  = RMII_BMC_OCP_TXD_0
  GND_B22  = RMII_BMC_OCP_TXD_1
  PETN2  = RMII_BMC_OCP_RX_ER
  PETP2  = RMII_OCP_BMC_RXD_0
  GND_B25  = RMII_OCP_BMC_RXD_1
  PETN3  = GND
  PETP3  = PECI_BMC
  GND_B28  = PVCCIO_PECI_BMC
  GND_B29  = SGPIO_DO_0
  PETN4  = SGPIO_CLK_0
  PETP4  = SGPIO_DI_0
  GND_B32  = SGPIO_LD_0
  PETN5  = GND
  PETP5  = SGPIO_DO_1
  GND_B35  = SGPIO_CLK_1
  PETN6  = SGPIO_DI_1
  PETP6  = SGPIO_LD_1
  GND_B38  = GND
  PETN7  = RST_SGPIO_RESET_N
  PETP7  = IRQ_SGPIO_INTR_N
  GND_B41  = P3V_BAT_R1
  \prsntb0#\  = FM_AC_PWR_BTN_N
  GND_B43  = TP_SPI_2_PLD_CLK
  PETN8  = TP_SPI_2_PLD_CS_N
  PETP8  = TP_SPI_2_PLD_IO0
  GND_B46  = TP_SPI_2_PLD_IO1
  PETN9  = TP_SPI_2_PLD_IO2
  PETP9  = TP_SPI_2_PLD_IO3
  GND_B49  = GND
  PETN10  = USB2_HOST_BMC_B_DP
  PETP10  = USB2_HOST_BMC_B_DN
  GND_B52  = GND
  PETN11  = USB2_8_DP
  PETP11  = USB2_8_DN
  GND_B55  = GND
  PETN12  = USB2_HUB_2_BUF_EXT_DP
  PETP12  = USB2_HUB_2_BUF_EXT_DN
  GND_B58  = GND
  PETN13  = USB3_PCH_TX_BUF_C_DP<4>
  PETP13  = USB3_PCH_TX_BUF_C_DN<4>
  GND_B61  = GND
  PETN14  = TP_PCIE_HPM_TXP<1>
  PETP14  = TP_PCIE_HPM_TXN<1>
  GND_B64  = GND
  PETN15  = P2E_MB_BMC_TX_C_DP<0>
  PETP15  = P2E_MB_BMC_TX_C_DN<0>
  GND_B67  = GND
  RFU1_NC_B68  = TP_PCIE_HPM_TXP<3>
  RFU1_NC_B69  = TP_PCIE_HPM_TXN<3>
  \prsntb3#\  = GND
  G1  = GND
  G2  = GND
  G3  = GND
  G4  = GND
  G5  = GND
  \perst2#\  = P12V_SCM
  \perst3#\  = P12V_SCM
  \wake#\  = GND
  RBT_ARB_IN  = GND
  RBT_ARB_OUT  = I3C_SPD_DDRABCD_CPU0_BMC_R_SCL
  SLOT_ID1  = I3C_SPD_DDRABCD_CPU0_BMC_R_SDA
  RBT_TX_EN  = I3C_SPD_DDREFGH_CPU0_BMC_R_SCL
  RBT_TXD1  = I3C_SPD_DDREFGH_CPU0_BMC_R_SDA
  RBT_TXD0  = I3C_SPD_DDRABCD_CPU1_BMC_R_SCL
  GND_OA10  = I3C_SPD_DDRABCD_CPU1_BMC_R_SDA
  REFCLKN3  = I3C_SPD_DDREFGH_CPU1_BMC_R_SCL
  REFCLKP3  = I3C_SPD_DDREFGH_CPU1_BMC_R_SDA
  GND_OA13  = GND
  RBT_CLK_IN  = VIRTUAL_RESEAT
  NIC_PWR_GOOD  = P12V_SCM
  MAIN_PWR_EN  = P12V_SCM
  \ld#\  = PRSNT0_N
  DATA_IN  = GND
  DATA_OUT  = UART_BMC_BIC_TX
  CLK  = UART_BMC_BIC_BUF_RX
  SLOT_ID0  = GND
  RBT_RXD1  = USB2_7_R_DP
  RBT_RXD0  = USB2_7_R_DN
  GND_OB10  = GND
  REFCLKN2  = RST_SRST_PLD_BMC_N
  REFCLKP2  = SPI_TPM_CS_N
  GND_OB13  = H_CPU_CATERR_LVC2_BMC_N
  RBT_CRS_DV  = FM_SOL_UART_CH_SEL_R

(kicad_pcb
	(version 20260206)
	(generator "pcbnew")
	(generator_version "10.0")
	(general
		(thickness 1.6)
		(legacy_teardrops no)
	)
	(paper "A4")
	(title_block
		(title "03242023_DA0F0TMBIJ0_F0T_Motherboard_J_brd_V01_OCP.brd")
		(comment 1 "Grand Teton / footprint 3077 of 6105 (J41), pads 1-42 of 175")
	)
	(layers
		(0 "F.Cu" signal "TOP")
		(4 "In1.Cu" signal "GND")
		(6 "In2.Cu" signal "IN1")
		(8 "In3.Cu" signal "GND1")
		(10 "In4.Cu" signal "IN2")
		(12 "In5.Cu" signal "GND2")
		(14 "In6.Cu" signal "IN3")
		(16 "In7.Cu" signal "GND3")
		(18 "In8.Cu" signal "VCC")
		(20 "In9.Cu" signal "VCC1")
		(22 "In10.Cu" signal "GND4")
		(24 "In11.Cu" signal "IN4")
		(26 "In12.Cu" signal "GND5")
		(28 "In13.Cu" signal "IN5")
		(30 "In14.Cu" signal "GND6")
		(32 "In15.Cu" signal "IN6")
		(34 "In16.Cu" signal "GND7")
		(2 "B.Cu" signal "BOTTOM")
		(9 "F.Adhes" user "F.Adhesive")
		(11 "B.Adhes" user "B.Adhesive")
		(13 "F.Paste" user "Package Geometry/Pastemask Top")
		(15 "B.Paste" user "Package Geometry/Pastemask Bottom")
		(5 "F.SilkS" user "Ref Des/Silkscreen Top")
		(7 "B.SilkS" user "Ref Des/Silkscreen Bottom")
		(1 "F.Mask" user "Board Geometry/Soldermask Top")
		(3 "B.Mask" user "Board Geometry/Soldermask Bottom")
		(17 "Dwgs.User" user "User.Drawings")
		(19 "Cmts.User" user "User.Comments")
		(21 "Eco1.User" user "User.Eco1")
		(23 "Eco2.User" user "User.Eco2")
		(25 "Edge.Cuts" user "Board Geometry/Outline")
		(27 "Margin" user)
		(31 "F.CrtYd" user "Package Geometry/Place Bound Top")
		(29 "B.CrtYd" user "Package Geometry/Place Bound Bottom")
		(35 "F.Fab" user "Ref Des/Assembly Top")
		(33 "B.Fab" user "Ref Des/Assembly Bottom")
	)
	(footprint ""
		(layer "F.Cu")
		(at 160.402016 -10.850118 -90)
		(property "Reference" "J41"
			(at -12.075414 24.511762 0)
			(unlocked yes)
			(layer "F.SilkS")
			(effects
				(font
					(size 0.7874 0.5842)
					(thickness 0.1524)
				)
				(justify left)
			)
		)
		(property "Value" ""
			(at 0 0 270)
			(layer "F.Fab")
			(effects
				(font
					(size 1.27 1.27)
				)
			)
		)
		(duplicate_pad_numbers_are_jumpers no)
		(pad "" np_thru_hole circle
			(at -0.599948 -32.079946 180)
			(size 1.1176 1.1176)
			(drill 1.1176)
			(layers "*.Cu" "*.Mask")
			(clearance 0.381)
			(thermal_gap 0.381)
		)
		(pad "" np_thru_hole circle
			(at 0.40005 32.085026 180)
			(size 1.1176 1.1176)
			(drill 1.1176)
			(layers "*.Cu" "*.Mask")
			(clearance 0.381)
			(thermal_gap 0.381)
		)
		(pad "A1" smd rect
			(at -2.750058 -18.465038 180)
			(size 0.381 1.4478)
			(layers "F.Cu" "F.Mask" "F.Paste")
			(net "SMB_OCP_SFF_3V3AUX_SCL_R0")
		)
		(pad "A2" smd rect
			(at -2.750058 -17.86509 180)
			(size 0.381 1.4478)
			(layers "F.Cu" "F.Mask" "F.Paste")
			(net "SMB_OCP_SFF_3V3AUX_SDA_R0")
		)
		(pad "A3" smd rect
			(at -2.750058 -17.264888 180)
			(size 0.381 1.4478)
			(layers "F.Cu" "F.Mask" "F.Paste")
			(net "SMB_HOST_3V3AUX_SCL_R0")
		)
		(pad "A4" smd rect
			(at -2.750058 -16.66494 180)
			(size 0.381 1.4478)
			(layers "F.Cu" "F.Mask" "F.Paste")
			(net "SMB_HOST_3V3AUX_SDA_R0")
		)
		(pad "A5" smd rect
			(at -2.750058 -16.064992 180)
			(size 0.381 1.4478)
			(layers "F.Cu" "F.Mask" "F.Paste")
			(net "SMB_VR_3V3AUX_SCL_R0")
		)
		(pad "A6" smd rect
			(at -2.750058 -15.465044 180)
			(size 0.381 1.4478)
			(layers "F.Cu" "F.Mask" "F.Paste")
			(net "SMB_VR_3V3AUX_SDA_R0")
		)
		(pad "A7" smd rect
			(at -2.750058 -14.865096 180)
			(size 0.381 1.4478)
			(layers "F.Cu" "F.Mask" "F.Paste")
			(net "SMB_SML1_PMBUS_3V3AUX_PCH_SCL_R")
		)
		(pad "A8" smd rect
			(at -2.750058 -14.264894 180)
			(size 0.381 1.4478)
			(layers "F.Cu" "F.Mask" "F.Paste")
			(net "SMB_SML1_PMBUS_3V3AUX_PCH_SDA_R")
		)
		(pad "A9" smd rect
			(at -2.750058 -13.664946 180)
			(size 0.381 1.4478)
			(layers "F.Cu" "F.Mask" "F.Paste")
			(net "I3C_BMC_SWB_SCL")
		)
		(pad "A10" smd rect
			(at -2.750058 -13.064998 180)
			(size 0.381 1.4478)
			(layers "F.Cu" "F.Mask" "F.Paste")
			(net "I3C_BMC_SWB_SDA")
		)
		(pad "A11" smd rect
			(at -2.750058 -12.46505 180)
			(size 0.381 1.4478)
			(layers "F.Cu" "F.Mask" "F.Paste")
			(net "SMB_OCP_V3_2_3V3AUX_SCL_R0")
		)
		(pad "A12" smd rect
			(at -2.750058 -11.865102 180)
			(size 0.381 1.4478)
			(layers "F.Cu" "F.Mask" "F.Paste")
			(net "SMB_OCP_V3_2_3V3AUX_SDA_R0")
		)
		(pad "A13" smd rect
			(at -2.750058 -11.2649 180)
			(size 0.381 1.4478)
			(layers "F.Cu" "F.Mask" "F.Paste")
			(net "GND")
		)
		(pad "A14" smd rect
			(at -2.750058 -10.664952 180)
			(size 0.381 1.4478)
			(layers "F.Cu" "F.Mask" "F.Paste")
			(net "CLK_100M_BMC_P3E_DP_R")
		)
		(pad "A15" smd rect
			(at -2.750058 -10.065004 180)
			(size 0.381 1.4478)
			(layers "F.Cu" "F.Mask" "F.Paste")
			(net "CLK_100M_BMC_P3E_DN_R")
		)
		(pad "A16" smd rect
			(at -2.750058 -9.465056 180)
			(size 0.381 1.4478)
			(layers "F.Cu" "F.Mask" "F.Paste")
			(net "GND")
		)
		(pad "A17" smd rect
			(at -2.750058 -8.865108 180)
			(size 0.381 1.4478)
			(layers "F.Cu" "F.Mask" "F.Paste")
			(net "P3E_PCH_BMC_TX_C_DP")
		)
		(pad "A18" smd rect
			(at -2.750058 -8.264906 180)
			(size 0.381 1.4478)
			(layers "F.Cu" "F.Mask" "F.Paste")
			(net "P3E_PCH_BMC_TX_C_DN")
		)
		(pad "A19" smd rect
			(at -2.750058 -7.664958 180)
			(size 0.381 1.4478)
			(layers "F.Cu" "F.Mask" "F.Paste")
			(net "GND")
		)
		(pad "A20" smd rect
			(at -2.750058 -7.06501 180)
			(size 0.381 1.4478)
			(layers "F.Cu" "F.Mask" "F.Paste")
			(net "P3E_PCH_BMC_RX_DP")
		)
		(pad "A21" smd rect
			(at -2.750058 -6.465062 180)
			(size 0.381 1.4478)
			(layers "F.Cu" "F.Mask" "F.Paste")
			(net "P3E_PCH_BMC_RX_DN")
		)
		(pad "A22" smd rect
			(at -2.750058 -5.865114 180)
			(size 0.381 1.4478)
			(layers "F.Cu" "F.Mask" "F.Paste")
			(net "GND")
		)
		(pad "A23" smd rect
			(at -2.750058 -5.264912 180)
			(size 0.381 1.4478)
			(layers "F.Cu" "F.Mask" "F.Paste")
			(net "SMB_PCIE0_3V3AUX_SCL")
		)
		(pad "A24" smd rect
			(at -2.750058 -4.664964 180)
			(size 0.381 1.4478)
			(layers "F.Cu" "F.Mask" "F.Paste")
			(net "SMB_PCIE0_3V3AUX_SDA")
		)
		(pad "A25" smd rect
			(at -2.750058 -4.065016 180)
			(size 0.381 1.4478)
			(layers "F.Cu" "F.Mask" "F.Paste")
			(net "SMB_SML0_3V3AUX_SCL_R1")
		)
		(pad "A26" smd rect
			(at -2.750058 -3.465068 180)
			(size 0.381 1.4478)
			(layers "F.Cu" "F.Mask" "F.Paste")
			(net "SMB_SML0_3V3AUX_SDA_R1")
		)
		(pad "A27" smd rect
			(at -2.750058 -2.86512 180)
			(size 0.381 1.4478)
			(layers "F.Cu" "F.Mask" "F.Paste")
			(net "SMB_1_PLD_3V3AUX_SCL_R3")
		)
		(pad "A28" smd rect
			(at -2.750058 -2.264918 180)
			(size 0.381 1.4478)
			(layers "F.Cu" "F.Mask" "F.Paste")
			(net "SMB_1_PLD_3V3AUX_SDA_R3")
		)
		(pad "A29" smd rect
			(at -2.750058 1.74498 180)
			(size 0.381 1.4478)
			(layers "F.Cu" "F.Mask" "F.Paste")
			(net "SMB_FAN_3V3AUX_SCL")
		)
		(pad "A30" smd rect
			(at -2.750058 2.344928 180)
			(size 0.381 1.4478)
			(layers "F.Cu" "F.Mask" "F.Paste")
			(net "SMB_FAN_3V3AUX_SDA")
		)
		(pad "A31" smd rect
			(at -2.750058 2.944876 180)
			(size 0.381 1.4478)
			(layers "F.Cu" "F.Mask" "F.Paste")
			(net "SMB_PCIE2_3V3AUX_SCL_R0")
		)
		(pad "A32" smd rect
			(at -2.750058 3.545078 180)
			(size 0.381 1.4478)
			(layers "F.Cu" "F.Mask" "F.Paste")
			(net "SMB_PCIE2_3V3AUX_SDA_R0")
		)
		(pad "A33" smd rect
			(at -2.750058 4.145026 180)
			(size 0.381 1.4478)
			(layers "F.Cu" "F.Mask" "F.Paste")
			(net "GND")
		)
		(pad "A34" smd rect
			(at -2.750058 4.744974 180)
			(size 0.381 1.4478)
			(layers "F.Cu" "F.Mask" "F.Paste")
			(net "JTAG_BMC_TCK")
		)
		(pad "A35" smd rect
			(at -2.750058 5.344922 180)
			(size 0.381 1.4478)
			(layers "F.Cu" "F.Mask" "F.Paste")
			(net "JTAG_BMC_TMS")
		)
		(pad "A36" smd rect
			(at -2.750058 5.945124 180)
			(size 0.381 1.4478)
			(layers "F.Cu" "F.Mask" "F.Paste")
			(net "JTAG_BMC_TDI")
		)
		(pad "A37" smd rect
			(at -2.750058 6.545072 180)
			(size 0.381 1.4478)
			(layers "F.Cu" "F.Mask" "F.Paste")
			(net "JTAG_BMC_TDO")
		)
		(pad "A38" smd rect
			(at -2.750058 7.14502 180)
			(size 0.381 1.4478)
			(layers "F.Cu" "F.Mask" "F.Paste")
			(net "SMB_PCIE3_3V3AUX_SCL_R")
		)
		(pad "A39" smd rect
			(at -2.750058 7.744968 180)
			(size 0.381 1.4478)
			(layers "F.Cu" "F.Mask" "F.Paste")
			(net "SMB_PCIE3_3V3AUX_SDA_R")
		)
		(pad "A40" smd rect
			(at -2.750058 8.344916 180)
			(size 0.381 1.4478)
			(layers "F.Cu" "F.Mask" "F.Paste")
			(net "SMB_S3M_CPU_3V3AUX_SCL_R0")
		)
	)
)
